# T6G (Grand Teton) — schematic netlist excerpt (pin names and nets, part order shuffled) for the footprints in the layout excerpt that follows; sources: Cadence DE-HDL packaged netlist, KiCad conversion of 04192023_DAF0TMB3IC0_F0TG_MB_C_brd_V02_OCP.brd

R31  Q_RES  4.7K 1% EMPTY  pkg 0402LF  page 131 : A = P3V3_OCP_SFF ; B = OCP_SFF_ID0
R6760  Q_RES  0 5% CHIP  pkg 0201LF  page 184 : A = SMB_RT_CPU0_P2_SDA ; B = SMB_RT_CPU0_P2_R_SDA
PC6587_2  Q_CAP  22UF 4V 20% X6S  pkg C0805  page 363 : A = P0V9_CPU0_RT_2D ; B = GND

(kicad_pcb
	(version 20260206)
	(generator "pcbnew")
	(generator_version "10.0")
	(general
		(thickness 1.6)
		(legacy_teardrops no)
	)
	(paper "A4")
	(title_block
		(title "04192023_DAF0TMB3IC0_F0TG_MB_C_brd_V02_OCP.brd")
		(comment 1 "Grand Teton / footprints 7037-7039 of 8354")
	)
	(layers
		(0 "F.Cu" signal "TOP")
		(4 "In1.Cu" signal "GND")
		(6 "In2.Cu" signal "IN1")
		(8 "In3.Cu" signal "GND1")
		(10 "In4.Cu" signal "IN2")
		(12 "In5.Cu" signal "GND2")
		(14 "In6.Cu" signal "IN3")
		(16 "In7.Cu" signal "GND3")
		(18 "In8.Cu" signal "VCC")
		(20 "In9.Cu" signal "VCC1")
		(22 "In10.Cu" signal "GND4")
		(24 "In11.Cu" signal "IN4")
		(26 "In12.Cu" signal "GND5")
		(28 "In13.Cu" signal "IN5")
		(30 "In14.Cu" signal "GND6")
		(32 "In15.Cu" signal "IN6")
		(34 "In16.Cu" signal "GND7")
		(2 "B.Cu" signal "BOTTOM")
		(9 "F.Adhes" user "F.Adhesive")
		(11 "B.Adhes" user "B.Adhesive")
		(13 "F.Paste" user "Package Geometry/Pastemask Top")
		(15 "B.Paste" user "Package Geometry/Pastemask Bottom")
		(5 "F.SilkS" user "Ref Des/Silkscreen Top")
		(7 "B.SilkS" user "Ref Des/Silkscreen Bottom")
		(1 "F.Mask" user "Board Geometry/Soldermask Top")
		(3 "B.Mask" user "Board Geometry/Soldermask Bottom")
		(17 "Dwgs.User" user "User.Drawings")
		(19 "Cmts.User" user "User.Comments")
		(21 "Eco1.User" user "User.Eco1")
		(23 "Eco2.User" user "User.Eco2")
		(25 "Edge.Cuts" user "Board Geometry/Outline")
		(27 "Margin" user)
		(31 "F.CrtYd" user "Package Geometry/Place Bound Top")
		(29 "B.CrtYd" user "Package Geometry/Place Bound Bottom")
		(35 "F.Fab" user "Ref Des/Assembly Top")
		(33 "B.Fab" user "Ref Des/Assembly Bottom")
	)
	(footprint ""
		(layer "B.Cu")
		(at 230.6828 -335.026 180)
		(property "Reference" "R6760"
			(at 0 0 0)
			(layer "B.SilkS")
			(hide yes)
			(effects
				(font
					(size 1.27 1.27)
				)
				(justify mirror)
			)
		)
		(property "Value" ""
			(at 0 0 0)
			(layer "B.Fab")
			(effects
				(font
					(size 1.27 1.27)
				)
				(justify mirror)
			)
		)
		(duplicate_pad_numbers_are_jumpers no)
		(fp_line
			(start 0.32512 0.175006)
			(end 0.32512 -0.175006)
			(stroke
				(width 0.1)
				(type default)
			)
			(layer "B.Fab")
		)
		(fp_line
			(start 0.32512 -0.175006)
			(end -0.32512 -0.175006)
			(stroke
				(width 0.1)
				(type default)
			)
			(layer "B.Fab")
		)
		(fp_line
			(start -0.32512 0.175006)
			(end 0.32512 0.175006)
			(stroke
				(width 0.1)
				(type default)
			)
			(layer "B.Fab")
		)
		(fp_line
			(start -0.32512 -0.175006)
			(end -0.32512 0.175006)
			(stroke
				(width 0.1)
				(type default)
			)
			(layer "B.Fab")
		)
		(pad "1" smd rect
			(at 0.2667 0)
			(size 0.3048 0.381)
			(layers "B.Cu" "B.Mask" "B.Paste")
			(net "SMB_RT_CPU0_P2_SDA")
		)
		(pad "2" smd rect
			(at -0.2667 0 180)
			(size 0.3048 0.381)
			(layers "B.Cu" "B.Mask" "B.Paste")
			(net "SMB_RT_CPU0_P2_R_SDA")
		)
	)
	(footprint ""
		(layer "B.Cu")
		(at 443.013592 -389.14832 -90)
		(property "Reference" "PC6587_2"
			(at 0 0 90)
			(layer "B.SilkS")
			(hide yes)
			(effects
				(font
					(size 1.27 1.27)
				)
				(justify mirror)
			)
		)
		(property "Value" ""
			(at 0 0 90)
			(layer "B.Fab")
			(effects
				(font
					(size 1.27 1.27)
				)
				(justify mirror)
			)
		)
		(duplicate_pad_numbers_are_jumpers no)
		(fp_line
			(start -1.524 0.762)
			(end 1.524 0.762)
			(stroke
				(width 0.1524)
				(type default)
			)
			(layer "B.SilkS")
		)
		(fp_line
			(start 1.524 0.762)
			(end 1.524 -0.762)
			(stroke
				(width 0.1524)
				(type default)
			)
			(layer "B.SilkS")
		)
		(fp_line
			(start -1.524 -0.762)
			(end -1.524 0.762)
			(stroke
				(width 0.1524)
				(type default)
			)
			(layer "B.SilkS")
		)
		(fp_line
			(start 1.524 -0.762)
			(end -1.524 -0.762)
			(stroke
				(width 0.1524)
				(type default)
			)
			(layer "B.SilkS")
		)
		(fp_line
			(start -1.1049 0.724916)
			(end -1.1049 -0.724916)
			(stroke
				(width 0.1)
				(type default)
			)
			(layer "B.Fab")
		)
		(fp_line
			(start 1.1049 0.724916)
			(end -1.1049 0.724916)
			(stroke
				(width 0.1)
				(type default)
			)
			(layer "B.Fab")
		)
		(fp_line
			(start -1.1049 -0.724916)
			(end 1.1049 -0.724916)
			(stroke
				(width 0.1)
				(type default)
			)
			(layer "B.Fab")
		)
		(fp_line
			(start 1.1049 -0.724916)
			(end 1.1049 0.724916)
			(stroke
				(width 0.1)
				(type default)
			)
			(layer "B.Fab")
		)
		(pad "1" smd rect
			(at 0.889 0 270)
			(size 1.016 1.27)
			(layers "B.Cu" "B.Mask" "B.Paste")
			(net "P0V9_CPU0_RT_2D")
		)
		(pad "2" smd rect
			(at -0.889 0 270)
			(size 1.016 1.27)
			(layers "B.Cu" "B.Mask" "B.Paste")
			(net "GND")
		)
	)
	(footprint ""
		(layer "B.Cu")
		(at 448.579748 -10.567162 -90)
		(property "Reference" "R31"
			(at 0 0 90)
			(layer "B.SilkS")
			(hide yes)
			(effects
				(font
					(size 1.27 1.27)
				)
				(justify mirror)
			)
		)
		(property "Value" ""
			(at 0 0 90)
			(layer "B.Fab")
			(effects
				(font
					(size 1.27 1.27)
				)
				(justify mirror)
			)
		)
		(duplicate_pad_numbers_are_jumpers no)
		(fp_line
			(start -0.7874 0.4064)
			(end 0.7874 0.4064)
			(stroke
				(width 0.1524)
				(type default)
			)
			(layer "B.SilkS")
		)
		(fp_line
			(start 0.7874 0.4064)
			(end 0.7874 -0.4064)
			(stroke
				(width 0.1524)
				(type default)
			)
			(layer "B.SilkS")
		)
		(fp_line
			(start -0.7874 -0.4064)
			(end -0.7874 0.4064)
			(stroke
				(width 0.1524)
				(type default)
			)
			(layer "B.SilkS")
		)
		(fp_line
			(start 0.7874 -0.4064)
			(end -0.7874 -0.4064)
			(stroke
				(width 0.1524)
				(type default)
			)
			(layer "B.SilkS")
		)
		(fp_line
			(start -0.67945 0.3048)
			(end -0.120396 0.3048)
			(stroke
				(width 0.1)
				(type default)
			)
			(layer "B.Fab")
		)
		(fp_line
			(start -0.120396 0.3048)
			(end -0.120396 0.2794)
			(stroke
				(width 0.1)
				(type default)
			)
			(layer "B.Fab")
		)
		(fp_line
			(start 0.12065 0.3048)
			(end 0.67945 0.3048)
			(stroke
				(width 0.1)
				(type default)
			)
			(layer "B.Fab")
		)
		(fp_line
			(start 0.67945 0.3048)
			(end 0.67945 -0.305054)
			(stroke
				(width 0.1)
				(type default)
			)
			(layer "B.Fab")
		)
		(fp_line
			(start -0.120396 0.2794)
			(end 0.12065 0.2794)
			(stroke
				(width 0.1)
				(type default)
			)
			(layer "B.Fab")
		)
		(fp_line
			(start 0.12065 0.2794)
			(end 0.12065 0.3048)
			(stroke
				(width 0.1)
				(type default)
			)
			(layer "B.Fab")
		)
		(fp_line
			(start -0.12065 -0.2794)
			(end -0.12065 -0.3048)
			(stroke
				(width 0.1)
				(type default)
			)
			(layer "B.Fab")
		)
		(fp_line
			(start 0.12065 -0.2794)
			(end -0.12065 -0.2794)
			(stroke
				(width 0.1)
				(type default)
			)
			(layer "B.Fab")
		)
		(fp_line
			(start -0.67945 -0.3048)
			(end -0.67945 0.3048)
			(stroke
				(width 0.1)
				(type default)
			)
			(layer "B.Fab")
		)
		(fp_line
			(start -0.12065 -0.3048)
			(end -0.67945 -0.3048)
			(stroke
				(width 0.1)
				(type default)
			)
			(layer "B.Fab")
		)
		(fp_line
			(start 0.12065 -0.305054)
			(end 0.12065 -0.2794)
			(stroke
				(width 0.1)
				(type default)
			)
			(layer "B.Fab")
		)
		(fp_line
			(start 0.67945 -0.305054)
			(end 0.12065 -0.305054)
			(stroke
				(width 0.1)
				(type default)
			)
			(layer "B.Fab")
		)
		(pad "1" smd circle
			(at 0.40005 0 90)
			(size 0 0)
			(layers "B.Cu" "B.Mask" "B.Paste")
			(net "P3V3_OCP_SFF")
		)
		(pad "2" smd circle
			(at -0.40005 0 90)
			(size 0 0)
			(layers "B.Cu" "B.Mask" "B.Paste")
			(net "OCP_SFF_ID0")
		)
	)
)
